FILE_TYPE = CONNECTIVITY;
{Allegro Design Entry HDL 17.4-2019 S026 (4007227) 1/17/2022}
"PAGE_NUMBER" = 101;
0"NC";
1"GND\g";
2"GND\g";
3"P3V3\g";
4"M_E_CPU1_SB_CB<7:0>";
5"M_E_CPU1_SB_DQ<31:0>";
6"M_E_CPU1_SA_DQ<31:0>";
7"M_E_CPU1_SB_DQS_DP<9:0>";
8"M_E_CPU1_SB_DQS_DN<9:0>";
9"M_E_CPU1_SA_DQS_DP<9:0>";
10"M_E_CPU1_SA_DQS_DN<9:0>";
11"M_E_CPU1_SA_CB<7:0>";
12"M_E_CPU1_SB_CA<6:0>";
13"M_E_CPU1_SA_CA<6:0>";
14"M_E_CPU1_SA_DQ<31>";
15"M_E_CPU1_SA_CB<7>";
16"M_E_CPU1_SA_CB<4>";
17"M_E_CPU1_SA_CB<1>";
18"M_E_CPU1_SB_CB<7>";
19"M_E_CPU1_SA_CA<0>";
20"M_E_CPU1_SB_CA<0>";
21"M_E_CPU1_SA_CA<1>";
22"M_E_CPU1_SB_CA<1>";
23"M_E_CPU1_SA_CA<2>";
24"M_E_CPU1_SB_CA<2>";
25"M_E_CPU1_SA_CA<3>";
26"M_E_CPU1_SB_CA<3>";
27"M_E_CPU1_SA_CA<4>";
28"M_E_CPU1_SB_CA<4>";
29"M_E_CPU1_SA_CA<5>";
30"M_E_CPU1_SB_CA<5>";
31"M_E_CPU1_SA_CA<6>";
32"M_E_CPU1_SB_CA<6>";
33"M_E_CPU1_SA_CB<6>";
34"M_E_CPU1_SA_CB<5>";
35"M_E_CPU1_SA_CB<3>";
36"M_E_CPU1_SA_CB<2>";
37"M_E_CPU1_SA_CB<0>";
38"M_E_CPU1_SB_CB<6>";
39"M_E_CPU1_SB_CB<5>";
40"M_E_CPU1_SB_CB<4>";
41"M_E_CPU1_CLK_DN<0>";
42"M_E_CPU1_SA_CS_N<0>";
43"M_E_CPU1_SA_CS_N<1>";
44"M_E_CPU1_SB_CS_N<1>";
45"M_E_CPU1_SA_DQ<30>";
46"M_E_CPU1_SA_DQ<29>";
47"M_E_CPU1_SA_DQ<28>";
48"M_E_CPU1_SA_DQ<27>";
49"M_E_CPU1_SA_DQ<26>";
50"M_E_CPU1_SA_DQ<25>";
51"M_E_CPU1_SA_DQ<24>";
52"M_E_CPU1_SA_DQ<23>";
53"M_E_CPU1_SA_DQ<22>";
54"M_E_CPU1_SA_DQ<21>";
55"M_E_CPU1_SA_DQ<20>";
56"M_E_CPU1_SA_DQ<19>";
57"M_E_CPU1_SA_DQ<18>";
58"M_E_CPU1_SA_DQ<17>";
59"M_E_CPU1_SA_DQ<16>";
60"M_E_CPU1_SA_DQ<15>";
61"M_E_CPU1_SA_DQ<14>";
62"M_E_CPU1_SA_DQ<13>";
63"M_E_CPU1_SA_DQ<12>";
64"M_E_CPU1_SA_DQ<11>";
65"M_E_CPU1_SA_DQ<10>";
66"M_E_CPU1_SA_DQ<8>";
67"M_E_CPU1_SA_DQ<7>";
68"M_E_CPU1_SA_DQ<6>";
69"M_E_CPU1_SA_DQ<5>";
70"M_E_CPU1_SA_DQ<4>";
71"M_E_CPU1_SA_DQ<3>";
72"M_E_CPU1_SA_DQ<2>";
73"M_E_CPU1_SA_DQ<1>";
74"M_E_CPU1_SA_DQ<0>";
75"M_E_CPU1_SB_DQ<31>";
76"M_E_CPU1_SB_DQ<30>";
77"M_E_CPU1_SB_DQ<29>";
78"M_E_CPU1_SB_DQ<28>";
79"M_E_CPU1_SB_DQ<27>";
80"M_E_CPU1_SB_DQ<26>";
81"M_E_CPU1_SB_DQ<25>";
82"M_E_CPU1_SB_DQ<24>";
83"M_E_CPU1_SB_DQ<23>";
84"M_E_CPU1_SB_DQ<22>";
85"M_E_CPU1_SB_DQ<21>";
86"M_E_CPU1_SB_DQ<20>";
87"M_E_CPU1_SB_DQ<19>";
88"M_E_CPU1_SB_DQ<18>";
89"M_E_CPU1_SB_DQ<17>";
90"M_E_CPU1_SB_DQ<16>";
91"M_E_CPU1_SB_DQ<15>";
92"M_E_CPU1_SB_DQ<14>";
93"M_E_CPU1_SB_DQ<12>";
94"M_E_CPU1_SB_DQ<11>";
95"M_E_CPU1_SB_DQ<10>";
96"M_E_CPU1_SB_DQ<9>";
97"M_E_CPU1_SB_DQ<8>";
98"M_E_CPU1_SB_DQ<7>";
99"M_E_CPU1_SB_DQ<6>";
100"M_E_CPU1_SB_DQ<5>";
101"M_E_CPU1_SB_DQ<4>";
102"M_E_CPU1_SB_DQ<3>";
103"M_E_CPU1_SB_DQ<2>";
104"M_E_CPU1_SB_DQ<1>";
105"M_E_CPU1_SB_DQ<0>";
106"M_E_CPU1_SB_RSP<0>";
107"M_E_CPU1_SA_PAR";
108"M_E_CPU1_SB_PAR";
109"M_E_CPU1_SA_DQS_DN<7>";
110"M_E_CPU1_SA_DQS_DP<6>";
111"M_E_CPU1_SB_DQS_DP<8>";
112"M_E_CPU1_SB_DQS_DN<8>";
113"M_E_CPU1_SB_DQS_DP<7>";
114"M_E_CPU1_SA_DQS_DN<0>";
115"M_E_CPU1_SA_DQS_DP<0>";
116"M_E_CPU1_SB_DQS_DN<0>";
117"M_E_CPU1_SB_DQS_DP<0>";
118"M_E_CPU1_SA_DQS_DN<1>";
119"M_E_CPU1_SA_DQS_DP<1>";
120"M_E_CPU1_SB_DQS_DN<1>";
121"M_E_CPU1_SB_DQS_DP<1>";
122"M_E_CPU1_SA_DQS_DN<2>";
123"M_E_CPU1_SA_DQS_DP<2>";
124"M_E_CPU1_SB_DQS_DN<2>";
125"M_E_CPU1_SB_DQS_DP<2>";
126"M_E_CPU1_SA_DQS_DN<3>";
127"M_E_CPU1_SA_DQS_DP<3>";
128"M_E_CPU1_SB_DQS_DN<3>";
129"M_E_CPU1_SB_DQS_DP<3>";
130"M_E_CPU1_SA_DQS_DN<4>";
131"M_E_CPU1_SA_DQS_DP<4>";
132"M_E_CPU1_SB_DQS_DN<4>";
133"M_E_CPU1_SB_DQS_DP<4>";
134"M_E_CPU1_SA_DQS_DN<5>";
135"M_E_CPU1_SA_DQS_DP<5>";
136"M_E_CPU1_SB_DQS_DN<5>";
137"M_E_CPU1_SB_DQS_DP<5>";
138"M_E_CPU1_SA_DQS_DN<6>";
139"M_E_CPU1_SB_DQS_DN<6>";
140"M_E_CPU1_SB_DQS_DP<6>";
141"M_E_CPU1_SA_DQS_DP<7>";
142"M_E_CPU1_SB_DQS_DN<7>";
143"M_E_CPU1_SA_DQS_DN<8>";
144"M_E_CPU1_SA_DQS_DP<8>";
145"M_E_CPU1_SA_DQS_DN<9>";
146"M_E_CPU1_SA_DQS_DP<9>";
147"M_E_CPU1_SB_DQS_DN<9>";
148"M_E_CPU1_SB_DQS_DP<9>";
149"M_E_CPU1_SA_RSP<0>";
150"PD_CHE_CPU1_DIMM_SAA";
151"M_E_CPU1_SA_DQ<9>";
152"M_E_CPU1_SB_DQ<13>";
153"PWRGD_CHAF_CPU1";
154"M_E_CPU1_SB_CS_N<0>";
155"M_E_CPU1_CLK_DP<0>";
156"M_E_CPU1_SB_CB<3>";
157"M_E_CPU1_SB_CB<2>";
158"M_E_CPU1_SB_CB<1>";
159"M_E_CPU1_SB_CB<0>";
160"M_E_CPU1_ALERT_N";
161"M_E_CPU1_RESET_N";
162"PD_CHE_CPU1_DIMM_SAA";
163"P12V_MEM_CPU1\g";
164"GND\g";
165"GND\g";
166"GND\g";
167"P3V3_AUX\g";
168"PWRGD_CHE_CPU1_DIMM";
169"I3C_SPD_DDRE_CPU1_SCL";
170"I3C_SPD_DDRE_CPU1_SDA";
171"I3C_SPD_DDRAF_CPU1_SCL";
172"I3C_SPD_DDRAF_CPU1_SDA";
%"VCC_CORE"
"1","(-8700,3675)","0","mstr_symbols","I1";
;
HDL_POWER"P3V3_AUX"
CDS_LIB"mstr_symbols"
VOLTAGE"3.3"
ROOM"PVCCINFAON_CPU1_CTRL";
"A"167;
%"TAP"
"1","(-6175,4450)","0","mstr_standard","I100";
;
CDS_LIB"mstr_standard"
BODY_TYPE"PLUMBING"
HDL_TAP"TRUE";
"B \NAC \NWC"6;
"S \NAC"
BN"7"67;
%"TAP"
"1","(-6175,4500)","0","mstr_standard","I101";
;
CDS_LIB"mstr_standard"
BODY_TYPE"PLUMBING"
HDL_TAP"TRUE";
"B \NAC \NWC"6;
"S \NAC"
BN"8"66;
%"TAP"
"1","(-6175,4550)","0","mstr_standard","I102";
;
CDS_LIB"mstr_standard"
BODY_TYPE"PLUMBING"
HDL_TAP"TRUE";
"B \NAC \NWC"6;
"S \NAC"
BN"9"151;
%"TAP"
"1","(-6175,4650)","0","mstr_standard","I103";
;
CDS_LIB"mstr_standard"
BODY_TYPE"PLUMBING"
HDL_TAP"TRUE";
"B \NAC \NWC"6;
"S \NAC"
BN"11"64;
%"TAP"
"1","(-6175,4600)","0","mstr_standard","I104";
;
CDS_LIB"mstr_standard"
BODY_TYPE"PLUMBING"
HDL_TAP"TRUE";
"B \NAC \NWC"6;
"S \NAC"
BN"10"65;
%"TAP"
"1","(-6175,4800)","0","mstr_standard","I105";
;
CDS_LIB"mstr_standard"
BODY_TYPE"PLUMBING"
HDL_TAP"TRUE";
"B \NAC \NWC"6;
"S \NAC"
BN"14"61;
%"TAP"
"1","(-6175,4750)","0","mstr_standard","I106";
;
CDS_LIB"mstr_standard"
BODY_TYPE"PLUMBING"
HDL_TAP"TRUE";
"B \NAC \NWC"6;
"S \NAC"
BN"13"62;
%"TAP"
"1","(-6175,4700)","0","mstr_standard","I107";
;
CDS_LIB"mstr_standard"
BODY_TYPE"PLUMBING"
HDL_TAP"TRUE";
"B \NAC \NWC"6;
"S \NAC"
BN"12"63;
%"TAP"
"1","(-6175,4850)","0","mstr_standard","I108";
;
CDS_LIB"mstr_standard"
BODY_TYPE"PLUMBING"
HDL_TAP"TRUE";
"B \NAC \NWC"6;
"S \NAC"
BN"15"60;
%"TAP"
"1","(-6175,4900)","0","mstr_standard","I109";
;
CDS_LIB"mstr_standard"
BODY_TYPE"PLUMBING"
HDL_TAP"TRUE";
"B \NAC \NWC"6;
"S \NAC"
BN"16"59;
%"TAP"
"1","(-7875,3450)","2","mstr_standard","I11";
;
CDS_LIB"mstr_standard"
BODY_TYPE"PLUMBING"
HDL_TAP"TRUE";
"B \NAC \NWC"4;
"S \NAC"
BN"0"159;
%"TAP"
"1","(-6175,4950)","0","mstr_standard","I110";
;
CDS_LIB"mstr_standard"
BODY_TYPE"PLUMBING"
HDL_TAP"TRUE";
"B \NAC \NWC"6;
"S \NAC"
BN"17"58;
%"TAP"
"1","(-6175,5000)","0","mstr_standard","I111";
;
CDS_LIB"mstr_standard"
BODY_TYPE"PLUMBING"
HDL_TAP"TRUE";
"B \NAC \NWC"6;
"S \NAC"
BN"18"57;
%"TAP"
"1","(-6175,5050)","0","mstr_standard","I112";
;
CDS_LIB"mstr_standard"
BODY_TYPE"PLUMBING"
HDL_TAP"TRUE";
"B \NAC \NWC"6;
"S \NAC"
BN"19"56;
%"TAP"
"1","(-6175,5100)","0","mstr_standard","I113";
;
CDS_LIB"mstr_standard"
BODY_TYPE"PLUMBING"
HDL_TAP"TRUE";
"B \NAC \NWC"6;
"S \NAC"
BN"20"55;
%"TAP"
"1","(-6175,5150)","0","mstr_standard","I114";
;
CDS_LIB"mstr_standard"
BODY_TYPE"PLUMBING"
HDL_TAP"TRUE";
"B \NAC \NWC"6;
"S \NAC"
BN"21"54;
%"TAP"
"1","(-6175,5250)","0","mstr_standard","I115";
;
CDS_LIB"mstr_standard"
BODY_TYPE"PLUMBING"
HDL_TAP"TRUE";
"B \NAC \NWC"6;
"S \NAC"
BN"23"52;
%"TAP"
"1","(-6175,5200)","0","mstr_standard","I116";
;
CDS_LIB"mstr_standard"
BODY_TYPE"PLUMBING"
HDL_TAP"TRUE";
"B \NAC \NWC"6;
"S \NAC"
BN"22"53;
%"TAP"
"1","(-6175,5300)","0","mstr_standard","I117";
;
CDS_LIB"mstr_standard"
BODY_TYPE"PLUMBING"
HDL_TAP"TRUE";
"B \NAC \NWC"6;
"S \NAC"
BN"24"51;
%"TAP"
"1","(-6175,5450)","0","mstr_standard","I118";
;
CDS_LIB"mstr_standard"
BODY_TYPE"PLUMBING"
HDL_TAP"TRUE";
"B \NAC \NWC"6;
"S \NAC"
BN"27"48;
%"TAP"
"1","(-6175,5400)","0","mstr_standard","I119";
;
CDS_LIB"mstr_standard"
BODY_TYPE"PLUMBING"
HDL_TAP"TRUE";
"B \NAC \NWC"6;
"S \NAC"
BN"26"49;
%"TAP"
"1","(-7875,3500)","2","mstr_standard","I12";
;
CDS_LIB"mstr_standard"
BODY_TYPE"PLUMBING"
HDL_TAP"TRUE";
"B \NAC \NWC"4;
"S \NAC"
BN"1"158;
%"TAP"
"1","(-6175,5350)","0","mstr_standard","I120";
;
CDS_LIB"mstr_standard"
BODY_TYPE"PLUMBING"
HDL_TAP"TRUE";
"B \NAC \NWC"6;
"S \NAC"
BN"25"50;
%"TAP"
"1","(-6175,5500)","0","mstr_standard","I121";
;
CDS_LIB"mstr_standard"
BODY_TYPE"PLUMBING"
HDL_TAP"TRUE";
"B \NAC \NWC"6;
"S \NAC"
BN"28"47;
%"TAP"
"1","(-6175,5550)","0","mstr_standard","I122";
;
CDS_LIB"mstr_standard"
BODY_TYPE"PLUMBING"
HDL_TAP"TRUE";
"B \NAC \NWC"6;
"S \NAC"
BN"29"46;
%"TAP"
"1","(-6175,5650)","0","mstr_standard","I123";
;
CDS_LIB"mstr_standard"
BODY_TYPE"PLUMBING"
HDL_TAP"TRUE";
"B \NAC \NWC"6;
"S \NAC"
BN"31"14;
%"TAP"
"1","(-6175,5600)","0","mstr_standard","I124";
;
CDS_LIB"mstr_standard"
BODY_TYPE"PLUMBING"
HDL_TAP"TRUE";
"B \NAC \NWC"6;
"S \NAC"
BN"30"45;
%"GND"
"1","(-6575,1250)","0","mstr_symbols","I126";
;
BOM_COST"MEM"
SIZE"1B"
CDS_LIB"mstr_symbols"
VOLTAGE"0.0"
BODY_TYPE"PLUMBING"
HDL_POWER"GND";
"A\NAC"1;
%"Q_RES"
"2","(-6575,1475)","0","pure_quanta","I127";
;
LOCATION"R6"
SEC"1"
PACK_TYPE"0402LF"
VALUE"54.9K"
TOLERANCE"1%"
MATERIAL"CHIP"
WATTAGE"1/16W"
SEC_TYPE"0402LF"
CDS_LIB"pure_quanta"
BOM_COST"MEM"
PART_NUMBER"CS35492FB03";
"A"
$PN"1"
XNET_PINS"3"150;
"B"
$PN"2"
XNET_PINS"2"1;
%"TAP"
"1","(-7875,3550)","2","mstr_standard","I13";
;
CDS_LIB"mstr_standard"
BODY_TYPE"PLUMBING"
HDL_TAP"TRUE";
"B \NAC \NWC"4;
"S \NAC"
BN"2"157;
%"TAP"
"1","(-7875,3600)","2","mstr_standard","I14";
;
CDS_LIB"mstr_standard"
BODY_TYPE"PLUMBING"
HDL_TAP"TRUE";
"B \NAC \NWC"4;
"S \NAC"
BN"3"156;
%"GND"
"1","(-2175,2250)","0","mstr_symbols","I140";
;
CDS_LIB"mstr_symbols"
SIZE"1B"
VOLTAGE"0.0"
BODY_TYPE"PLUMBING"
HDL_POWER"GND";
"A\NAC"166;
%"GND"
"1","(-375,2075)","0","mstr_symbols","I141";
;
CDS_LIB"mstr_symbols"
SIZE"1B"
VOLTAGE"0.0"
BODY_TYPE"PLUMBING"
HDL_POWER"GND";
"A\NAC"165;
%"TAP"
"1","(-7875,3650)","2","mstr_standard","I15";
;
CDS_LIB"mstr_standard"
BODY_TYPE"PLUMBING"
HDL_TAP"TRUE";
"B \NAC \NWC"4;
"S \NAC"
BN"4"40;
%"TAP"
"1","(-7875,3700)","2","mstr_standard","I16";
;
CDS_LIB"mstr_standard"
BODY_TYPE"PLUMBING"
HDL_TAP"TRUE";
"B \NAC \NWC"4;
"S \NAC"
BN"5"39;
%"TAP"
"1","(-7875,3750)","2","mstr_standard","I17";
;
CDS_LIB"mstr_standard"
BODY_TYPE"PLUMBING"
HDL_TAP"TRUE";
"B \NAC \NWC"4;
"S \NAC"
BN"6"38;
%"SCONN288_DDR506112002KQ"
"3","(-1275,4000)","0","pure_quanta","I175";
;
LOCATION"J32"
$SEC"3"
CDS_SEC"3"
PART_TYPE"SMLF"
MATERIAL"IO"
VALUE"SCONN288_DDR506112002KQ"
CDS_LMAN_SYM_OUTLINE"-450,1800,450,-1750"
NEEDS_NO_SIZE"TRUE"
CDS_LIB"pure_quanta"
PART_NUMBER"DFHST8FS479";
"G3"
$PN"G3"165;
"G2"
$PN"G2"165;
"G1"
$PN"G1"165;
"VSS62"
$PN"141"165;
"VSS61"
$PN"139"165;
"VSS60"
$PN"136"165;
"VSS58"
$PN"132"165;
"VSS104"
$PN"240"166;
"VSS102"
$PN"235"166;
"VSS100"
$PN"230"166;
"VIN_BULK2"
$PN"146"163;
"VIN_BULK1"
$PN"145"163;
"VIN_BULK0"
$PN"1"163;
"VSS126"
$PN"288"166;
"VSS125"
$PN"286"166;
"VSS124"
$PN"284"166;
"VSS123"
$PN"281"166;
"VSS122"
$PN"279"166;
"VSS121"
$PN"277"166;
"VSS120"
$PN"275"166;
"VSS119"
$PN"273"166;
"VSS118"
$PN"270"166;
"VSS117"
$PN"268"166;
"VSS116"
$PN"266"166;
"VSS115"
$PN"264"166;
"VSS114"
$PN"262"166;
"VSS113"
$PN"259"166;
"VSS112"
$PN"257"166;
"VSS111"
$PN"255"166;
"VSS110"
$PN"253"166;
"VSS109"
$PN"251"166;
"VSS108"
$PN"248"166;
"VSS107"
$PN"246"166;
"VSS106"
$PN"244"166;
"VSS105"
$PN"242"166;
"VSS103"
$PN"237"166;
"VSS101"
$PN"233"166;
"VSS99"
$PN"228"166;
"VSS98"
$PN"226"166;
"VSS97"
$PN"224"166;
"VSS96"
$PN"222"166;
"VSS95"
$PN"219"166;
"VSS94"
$PN"216"166;
"VSS93"
$PN"214"166;
"VSS92"
$PN"212"166;
"VSS91"
$PN"210"166;
"VSS90"
$PN"208"166;
"VSS89"
$PN"206"166;
"VSS88"
$PN"204"166;
"VSS87"
$PN"202"166;
"VSS86"
$PN"199"166;
"VSS85"
$PN"197"166;
"VSS84"
$PN"195"166;
"VSS83"
$PN"193"166;
"VSS82"
$PN"191"166;
"VSS81"
$PN"188"166;
"VSS80"
$PN"186"166;
"VSS79"
$PN"184"166;
"VSS78"
$PN"182"166;
"VSS77"
$PN"180"166;
"VSS76"
$PN"177"166;
"VSS75"
$PN"175"166;
"VSS74"
$PN"173"166;
"VSS73"
$PN"171"166;
"VSS72"
$PN"169"166;
"VSS71"
$PN"166"166;
"VSS70"
$PN"164"166;
"VSS69"
$PN"162"166;
"VSS68"
$PN"160"166;
"VSS67"
$PN"158"166;
"VSS66"
$PN"155"166;
"VSS65"
$PN"153"166;
"VSS64"
$PN"151"166;
"VSS63"
$PN"143"165;
"VSS59"
$PN"134"165;
"VSS57"
$PN"130"165;
"VSS56"
$PN"128"165;
"VSS55"
$PN"125"165;
"VSS54"
$PN"123"165;
"VSS53"
$PN"121"165;
"VSS52"
$PN"119"165;
"VSS51"
$PN"117"165;
"VSS50"
$PN"114"165;
"VSS49"
$PN"112"165;
"VSS48"
$PN"110"165;
"VSS47"
$PN"108"165;
"VSS46"
$PN"106"165;
"VSS45"
$PN"103"165;
"VSS44"
$PN"101"165;
"VSS43"
$PN"99"165;
"VSS42"
$PN"97"165;
"VSS41"
$PN"95"165;
"VSS40"
$PN"92"165;
"VSS39"
$PN"90"165;
"VSS38"
$PN"88"165;
"VSS37"
$PN"85"165;
"VSS36"
$PN"83"165;
"VSS35"
$PN"81"165;
"VSS34"
$PN"79"165;
"VSS33"
$PN"77"165;
"VSS32"
$PN"75"165;
"VSS31"
$PN"73"165;
"VSS30"
$PN"71"165;
"VSS29"
$PN"69"165;
"VSS28"
$PN"67"165;
"VSS27"
$PN"65"165;
"VSS26"
$PN"63"165;
"VSS25"
$PN"61"165;
"VSS24"
$PN"59"165;
"VSS23"
$PN"57"165;
"VSS22"
$PN"54"165;
"VSS21"
$PN"52"165;
"VSS20"
$PN"50"165;
"VSS19"
$PN"48"165;
"VSS18"
$PN"46"165;
"VSS17"
$PN"43"165;
"VSS16"
$PN"41"165;
"VSS15"
$PN"39"165;
"VSS14"
$PN"37"165;
"VSS13"
$PN"35"165;
"VSS12"
$PN"32"165;
"VSS11"
$PN"30"165;
"VSS10"
$PN"28"165;
"VSS9"
$PN"26"165;
"VSS8"
$PN"24"165;
"VSS7"
$PN"21"165;
"VSS6"
$PN"19"165;
"VSS5"
$PN"17"165;
"VSS4"
$PN"15"165;
"VSS3"
$PN"13"165;
"VSS2"
$PN"10"165;
"VSS1"
$PN"8"165;
"VSS0"
$PN"6"165;
%"TAP"
"1","(-7875,3900)","2","mstr_standard","I18";
;
CDS_LIB"mstr_standard"
BODY_TYPE"PLUMBING"
HDL_TAP"TRUE";
"B \NAC \NWC"11;
"S \NAC"
BN"0"37;
%"Q_CAP"
"1","(-8800,3475)","2","pure_quanta","I185";
;
LOCATION"C152"
$SEC"1"
CDS_SEC"1"
PACK_TYPE"0402"
VALUE"0.1UF"
VOLTAGE"25V"
TOLERANCE"10%"
MATERIAL"X7R"
BOM_COST"MEM"
CDS_LIB"pure_quanta"
ROOM""
PART_NUMBER"CH4104K1B00";
"B"
$PN"2"2;
"A"
$PN"1"167;
%"GND"
"1","(-8800,3250)","0","mstr_symbols","I186";
;
CDS_LIB"mstr_symbols"
SIZE"1B"
BOM_COST"MEM"
VOLTAGE"0"
ROOM"MEM_EFGH_DECOUPLING_CAPS"
BODY_TYPE"PLUMBING"
HDL_POWER"GND";
"A\NAC"2;
%"Q_RES"
"1","(-8625,2400)","2","pure_quanta","I188";
;
LOCATION"R307"
$SEC"1"
CDS_SEC"1"
VALUE"1K"
TOLERANCE"1%"
CDS_LIB"pure_quanta"
BOM_COST"MEM"
WATTAGE"1/16W"
MATERIAL"CHIP"
PACK_TYPE"0402LF"
ROOM""
PART_NUMBER"CS21002FB06";
"B"
$PN"2"153;
"A"
$PN"1"168;
%"VCC_CORE"
"1","(-8500,2725)","0","mstr_symbols","I189";
;
HDL_POWER"P3V3"
CDS_LIB"mstr_symbols"
VOLTAGE"3.3"
ROOM"PVCCINFAON_CPU0_CTRL";
"A"3;
%"TAP"
"1","(-7875,3800)","2","mstr_standard","I19";
;
CDS_LIB"mstr_standard"
BODY_TYPE"PLUMBING"
HDL_TAP"TRUE";
"B \NAC \NWC"4;
"S \NAC"
BN"7"18;
%"Q_RES"
"2","(-8500,2550)","0","pure_quanta","I190";
;
LOCATION"R107"
$SEC"1"
CDS_SEC"1"
PACK_TYPE"0402LF"
MATERIAL"EMPTY"
TOLERANCE"1%"
WATTAGE"1/16W"
VALUE"1K"
BOM_COST"MEM"
CDS_LIB"pure_quanta"
ROOM""
PART_NUMBER"CS21002FB06";
"A"
$PN"1"3;
"B"
$PN"2"168;
%"TAP"
"1","(-3475,3875)","0","mstr_standard","I192";
;
CDS_LIB"mstr_standard"
BODY_TYPE"PLUMBING"
HDL_TAP"TRUE";
"B \NAC \NWC"9;
"S \NAC"
BN"0"115;
%"TAP"
"1","(-3275,4025)","0","mstr_standard","I193";
;
CDS_LIB"mstr_standard"
BODY_TYPE"PLUMBING"
HDL_TAP"TRUE";
"B \NAC \NWC"10;
"S \NAC"
BN"2"122;
%"TAP"
"1","(-3275,4625)","0","mstr_standard","I198";
;
CDS_LIB"mstr_standard"
BODY_TYPE"PLUMBING"
HDL_TAP"TRUE";
"B \NAC \NWC"10;
"S \NAC"
BN"8"143;
%"TAP"
"1","(-3275,4725)","0","mstr_standard","I199";
;
CDS_LIB"mstr_standard"
BODY_TYPE"PLUMBING"
HDL_TAP"TRUE";
"B \NAC \NWC"10;
"S \NAC"
BN"9"145;
%"TAP"
"1","(-7875,4000)","2","mstr_standard","I20";
;
CDS_LIB"mstr_standard"
BODY_TYPE"PLUMBING"
HDL_TAP"TRUE";
"B \NAC \NWC"11;
"S \NAC"
BN"2"36;
%"TAP"
"1","(-3275,4425)","0","mstr_standard","I200";
;
CDS_LIB"mstr_standard"
BODY_TYPE"PLUMBING"
HDL_TAP"TRUE";
"B \NAC \NWC"10;
"S \NAC"
BN"6"138;
%"TAP"
"1","(-3275,4525)","0","mstr_standard","I201";
;
CDS_LIB"mstr_standard"
BODY_TYPE"PLUMBING"
HDL_TAP"TRUE";
"B \NAC \NWC"10;
"S \NAC"
BN"7"109;
%"TAP"
"1","(-3275,4325)","0","mstr_standard","I202";
;
CDS_LIB"mstr_standard"
BODY_TYPE"PLUMBING"
HDL_TAP"TRUE";
"B \NAC \NWC"10;
"S \NAC"
BN"5"134;
%"TAP"
"1","(-3475,4775)","0","mstr_standard","I203";
;
CDS_LIB"mstr_standard"
BODY_TYPE"PLUMBING"
HDL_TAP"TRUE";
"B \NAC \NWC"9;
"S \NAC"
BN"9"146;
%"TAP"
"1","(-3475,4675)","0","mstr_standard","I204";
;
CDS_LIB"mstr_standard"
BODY_TYPE"PLUMBING"
HDL_TAP"TRUE";
"B \NAC \NWC"9;
"S \NAC"
BN"8"144;
%"TAP"
"1","(-3475,4575)","0","mstr_standard","I205";
;
CDS_LIB"mstr_standard"
BODY_TYPE"PLUMBING"
HDL_TAP"TRUE";
"B \NAC \NWC"9;
"S \NAC"
BN"7"141;
%"TAP"
"1","(-3475,4475)","0","mstr_standard","I206";
;
CDS_LIB"mstr_standard"
BODY_TYPE"PLUMBING"
HDL_TAP"TRUE";
"B \NAC \NWC"9;
"S \NAC"
BN"6"110;
%"TAP"
"1","(-3475,4375)","0","mstr_standard","I207";
;
CDS_LIB"mstr_standard"
BODY_TYPE"PLUMBING"
HDL_TAP"TRUE";
"B \NAC \NWC"9;
"S \NAC"
BN"5"135;
%"TAP"
"1","(-3275,4225)","0","mstr_standard","I208";
;
CDS_LIB"mstr_standard"
BODY_TYPE"PLUMBING"
HDL_TAP"TRUE";
"B \NAC \NWC"10;
"S \NAC"
BN"4"130;
%"TAP"
"1","(-3275,4125)","0","mstr_standard","I209";
;
CDS_LIB"mstr_standard"
BODY_TYPE"PLUMBING"
HDL_TAP"TRUE";
"B \NAC \NWC"10;
"S \NAC"
BN"3"126;
%"TAP"
"1","(-7875,3950)","2","mstr_standard","I21";
;
CDS_LIB"mstr_standard"
BODY_TYPE"PLUMBING"
HDL_TAP"TRUE";
"B \NAC \NWC"11;
"S \NAC"
BN"1"17;
%"TAP"
"1","(-3275,3925)","0","mstr_standard","I210";
;
CDS_LIB"mstr_standard"
BODY_TYPE"PLUMBING"
HDL_TAP"TRUE";
"B \NAC \NWC"10;
"S \NAC"
BN"1"118;
%"TAP"
"1","(-3275,3825)","0","mstr_standard","I211";
;
CDS_LIB"mstr_standard"
BODY_TYPE"PLUMBING"
HDL_TAP"TRUE";
"B \NAC \NWC"10;
"S \NAC"
BN"0"114;
%"TAP"
"1","(-3475,4275)","0","mstr_standard","I212";
;
CDS_LIB"mstr_standard"
BODY_TYPE"PLUMBING"
HDL_TAP"TRUE";
"B \NAC \NWC"9;
"S \NAC"
BN"4"131;
%"TAP"
"1","(-3475,4175)","0","mstr_standard","I213";
;
CDS_LIB"mstr_standard"
BODY_TYPE"PLUMBING"
HDL_TAP"TRUE";
"B \NAC \NWC"9;
"S \NAC"
BN"3"127;
%"TAP"
"1","(-3475,4075)","0","mstr_standard","I214";
;
CDS_LIB"mstr_standard"
BODY_TYPE"PLUMBING"
HDL_TAP"TRUE";
"B \NAC \NWC"9;
"S \NAC"
BN"2"123;
%"TAP"
"1","(-3475,3975)","0","mstr_standard","I215";
;
CDS_LIB"mstr_standard"
BODY_TYPE"PLUMBING"
HDL_TAP"TRUE";
"B \NAC \NWC"9;
"S \NAC"
BN"1"119;
%"TAP"
"1","(-3275,3575)","0","mstr_standard","I216";
;
CDS_LIB"mstr_standard"
BODY_TYPE"PLUMBING"
HDL_TAP"TRUE";
"B \NAC \NWC"8;
"S \NAC"
BN"8"112;
%"TAP"
"1","(-3275,3675)","0","mstr_standard","I217";
;
CDS_LIB"mstr_standard"
BODY_TYPE"PLUMBING"
HDL_TAP"TRUE";
"B \NAC \NWC"8;
"S \NAC"
BN"9"147;
%"TAP"
"1","(-3275,3375)","0","mstr_standard","I218";
;
CDS_LIB"mstr_standard"
BODY_TYPE"PLUMBING"
HDL_TAP"TRUE";
"B \NAC \NWC"8;
"S \NAC"
BN"6"139;
%"TAP"
"1","(-3275,3475)","0","mstr_standard","I219";
;
CDS_LIB"mstr_standard"
BODY_TYPE"PLUMBING"
HDL_TAP"TRUE";
"B \NAC \NWC"8;
"S \NAC"
BN"7"142;
%"TAP"
"1","(-7875,4050)","2","mstr_standard","I22";
;
CDS_LIB"mstr_standard"
BODY_TYPE"PLUMBING"
HDL_TAP"TRUE";
"B \NAC \NWC"11;
"S \NAC"
BN"3"35;
%"TAP"
"1","(-3475,3725)","0","mstr_standard","I220";
;
CDS_LIB"mstr_standard"
BODY_TYPE"PLUMBING"
HDL_TAP"TRUE";
"B \NAC \NWC"7;
"S \NAC"
BN"9"148;
%"TAP"
"1","(-3475,3625)","0","mstr_standard","I221";
;
CDS_LIB"mstr_standard"
BODY_TYPE"PLUMBING"
HDL_TAP"TRUE";
"B \NAC \NWC"7;
"S \NAC"
BN"8"111;
%"TAP"
"1","(-3475,3525)","0","mstr_standard","I222";
;
CDS_LIB"mstr_standard"
BODY_TYPE"PLUMBING"
HDL_TAP"TRUE";
"B \NAC \NWC"7;
"S \NAC"
BN"7"113;
%"TAP"
"1","(-3475,3425)","0","mstr_standard","I223";
;
CDS_LIB"mstr_standard"
BODY_TYPE"PLUMBING"
HDL_TAP"TRUE";
"B \NAC \NWC"7;
"S \NAC"
BN"6"140;
%"TAP"
"1","(-3475,3325)","0","mstr_standard","I224";
;
CDS_LIB"mstr_standard"
BODY_TYPE"PLUMBING"
HDL_TAP"TRUE";
"B \NAC \NWC"7;
"S \NAC"
BN"5"137;
%"TAP"
"1","(-3275,3075)","0","mstr_standard","I225";
;
CDS_LIB"mstr_standard"
BODY_TYPE"PLUMBING"
HDL_TAP"TRUE";
"B \NAC \NWC"8;
"S \NAC"
BN"3"128;
%"TAP"
"1","(-3275,3275)","0","mstr_standard","I226";
;
CDS_LIB"mstr_standard"
BODY_TYPE"PLUMBING"
HDL_TAP"TRUE";
"B \NAC \NWC"8;
"S \NAC"
BN"5"136;
%"TAP"
"1","(-3275,3175)","0","mstr_standard","I227";
;
CDS_LIB"mstr_standard"
BODY_TYPE"PLUMBING"
HDL_TAP"TRUE";
"B \NAC \NWC"8;
"S \NAC"
BN"4"132;
%"TAP"
"1","(-3275,2875)","0","mstr_standard","I228";
;
CDS_LIB"mstr_standard"
BODY_TYPE"PLUMBING"
HDL_TAP"TRUE";
"B \NAC \NWC"8;
"S \NAC"
BN"1"120;
%"TAP"
"1","(-3275,2975)","0","mstr_standard","I229";
;
CDS_LIB"mstr_standard"
BODY_TYPE"PLUMBING"
HDL_TAP"TRUE";
"B \NAC \NWC"8;
"S \NAC"
BN"2"124;
%"TAP"
"1","(-7875,4100)","2","mstr_standard","I23";
;
CDS_LIB"mstr_standard"
BODY_TYPE"PLUMBING"
HDL_TAP"TRUE";
"B \NAC \NWC"11;
"S \NAC"
BN"4"16;
%"TAP"
"1","(-3475,3225)","0","mstr_standard","I230";
;
CDS_LIB"mstr_standard"
BODY_TYPE"PLUMBING"
HDL_TAP"TRUE";
"B \NAC \NWC"7;
"S \NAC"
BN"4"133;
%"TAP"
"1","(-3475,3125)","0","mstr_standard","I231";
;
CDS_LIB"mstr_standard"
BODY_TYPE"PLUMBING"
HDL_TAP"TRUE";
"B \NAC \NWC"7;
"S \NAC"
BN"3"129;
%"TAP"
"1","(-3475,3025)","0","mstr_standard","I232";
;
CDS_LIB"mstr_standard"
BODY_TYPE"PLUMBING"
HDL_TAP"TRUE";
"B \NAC \NWC"7;
"S \NAC"
BN"2"125;
%"TAP"
"1","(-3475,2925)","0","mstr_standard","I233";
;
CDS_LIB"mstr_standard"
BODY_TYPE"PLUMBING"
HDL_TAP"TRUE";
"B \NAC \NWC"7;
"S \NAC"
BN"1"121;
%"TAP"
"1","(-3475,2825)","0","mstr_standard","I234";
;
CDS_LIB"mstr_standard"
BODY_TYPE"PLUMBING"
HDL_TAP"TRUE";
"B \NAC \NWC"7;
"S \NAC"
BN"0"117;
%"TAP"
"1","(-3275,2775)","0","mstr_standard","I235";
;
CDS_LIB"mstr_standard"
BODY_TYPE"PLUMBING"
HDL_TAP"TRUE";
"B \NAC \NWC"8;
"S \NAC"
BN"0"116;
%"SCONN288_DDR506112002KQ"
"2","(-4425,3775)","0","pure_quanta","I236";
;
LOCATION"J32"
$SEC"2"
CDS_SEC"2"
MATERIAL"IO"
PART_TYPE"SMLF"
VALUE"SCONN288_DDR506112002KQ"
CDS_LMAN_SYM_OUTLINE"-600,1150,600,-1150"
NEEDS_NO_SIZE"TRUE"
CDS_LIB"pure_quanta"
PART_NUMBER"DFHST8FS479";
"DQS7_A_C||TDQS7_A_C \B"
$PN"178"109;
"DQS6_A_T||TDQS6_A_T"
$PN"168"110;
"DQS8_B_T||TDQS8_B_T"
$PN"283"111;
"DQS8_B_C||TDQS8_B_C \B"
$PN"282"112;
"DQS7_B_T||TDQS7_B_T"
$PN"272"113;
"DQS0_A_C \B"
$PN"12"114;
"DQS0_A_T"
$PN"11"115;
"DQS0_B_C \B"
$PN"105"116;
"DQS0_B_T"
$PN"104"117;
"DQS1_A_C \B"
$PN"23"118;
"DQS1_A_T"
$PN"22"119;
"DQS1_B_C \B"
$PN"116"120;
"DQS1_B_T"
$PN"115"121;
"DQS2_A_C \B"
$PN"34"122;
"DQS2_A_T"
$PN"33"123;
"DQS2_B_C \B"
$PN"127"124;
"DQS2_B_T"
$PN"126"125;
"DQS3_A_C \B"
$PN"45"126;
"DQS3_A_T"
$PN"44"127;
"DQS3_B_C \B"
$PN"138"128;
"DQS3_B_T"
$PN"137"129;
"DQS4_A_C \B"
$PN"56"130;
"DQS4_A_T"
$PN"55"131;
"DQS4_B_C \B"
$PN"238"132;
"DQS4_B_T"
$PN"239"133;
"DQS5_A_C||TDQS5_A_C||DQS5_A_T||TDQS5_A_T \B"
$PN"156"134;
"DQS5_A_T||TDQS5_A_T"
$PN"157"135;
"DQS5_B_C||TDQS5_B_C \B"
$PN"249"136;
"DQS5_B_T||TDQS5_B_T"
$PN"250"137;
"DQS6_A_C||TDQS6_A_C||DQS6_A_T||TDQS6_A_T \B"
$PN"167"138;
"DQS6_B_C||TDQS6_B_C \B"
$PN"260"139;
"DQS6_B_T||TDQS6_B_T"
$PN"261"140;
"DQS7_A_T||TDQS7_A_T"
$PN"179"141;
"DQS7_B_C||TDQS7_B_C \B"
$PN"271"142;
"DQS8_A_C||TDQS8_A_C \B"
$PN"189"143;
"DQS8_A_T||TDQS8_A_T"
$PN"190"144;
"DQS9_A_C||TDQS9_A_C \B"
$PN"200"145;
"DQS9_A_T||TDQS9_A_T"
$PN"201"146;
"DQS9_B_C||TDQS9_B_C \B"
$PN"94"147;
"DQS9_B_T||TDQS9_B_T||DBI4_B_N"
$PN"93"148;
%"GND"
"1","(-2875,5825)","0","pure_quanta_power","I237";
;
CDS_LIB"pure_quanta_power"
BOM_COST"MEM"
SIZE"1B"
ROOM"MEM_EFGH_DECOUPLING_CAPS"
HDL_POWER"GND";
"A<SIZE-1..0>\NAC"164;
%"Q_CAP"
"1","(-2875,6175)","2","pure_quanta","I238";
;
LOCATION"C183"
$SEC"1"
CDS_SEC"1"
PACK_TYPE"C0805"
VOLTAGE"25V"
VALUE"10UF"
TOLERANCE"10%"
MATERIAL"X6S"
CDS_LIB"pure_quanta"
BOM_COST"MEM"
ROOM""
PART_NUMBER"CH6104KEA00";
"B"
$PN"2"164;
"A"
$PN"1"163;
%"Q_CAP"
"1","(-2300,6175)","2","pure_quanta","I239";
;
LOCATION"C509"
$SEC"1"
CDS_SEC"1"
VALUE"10UF"
VOLTAGE"25V"
TOLERANCE"10%"
PACK_TYPE"C0805"
MATERIAL"X6S"
CDS_LIB"pure_quanta"
BOM_COST"MEM"
ROOM""
PART_NUMBER"CH6104KEA00";
"B"
$PN"2"164;
"A"
$PN"1"163;
%"TAP"
"1","(-7875,4150)","2","mstr_standard","I24";
;
CDS_LIB"mstr_standard"
BODY_TYPE"PLUMBING"
HDL_TAP"TRUE";
"B \NAC \NWC"11;
"S \NAC"
BN"5"34;
%"UNIVERSAL_POWER"
"1","(-2875,6500)","0","pure_quanta_power","I240";
;
HDL_POWER"P12V_MEM_CPU1"
CDS_LIB"pure_quanta_power";
"A"163;
%"Q_RES"
"1","(-7925,2875)","0","pure_quanta","I242";
;
LOCATION"R1584"
$SEC"1"
CDS_SEC"1"
VALUE"49.9"
CDS_LIB"pure_quanta"
TOLERANCE"1%"
WATTAGE"1/16W"
PACK_TYPE"0402LF"
MATERIAL"CHIP"
PART_NUMBER"CS04992FB07";
"B"
$PN"2"169;
"A"
$PN"1"171;
%"Q_RES"
"1","(-8300,3100)","0","pure_quanta","I243";
;
LOCATION"R1701"
$SEC"1"
CDS_SEC"1"
VALUE"10"
MATERIAL"CHIP"
PACK_TYPE"0402LF"
CDS_LIB"pure_quanta"
TOLERANCE"1%"
WATTAGE"1/16W"
PART_NUMBER"CS01002FB07";
"B"
$PN"2"170;
"A"
$PN"1"172;
%"TAP"
"1","(-7875,4200)","2","mstr_standard","I34";
;
CDS_LIB"mstr_standard"
BODY_TYPE"PLUMBING"
HDL_TAP"TRUE";
"B \NAC \NWC"11;
"S \NAC"
BN"6"33;
%"TAP"
"1","(-7875,4250)","2","mstr_standard","I35";
;
CDS_LIB"mstr_standard"
BODY_TYPE"PLUMBING"
HDL_TAP"TRUE";
"B \NAC \NWC"11;
"S \NAC"
BN"7"15;
%"TAP"
"1","(-7875,5000)","2","mstr_standard","I36";
;
CDS_LIB"mstr_standard"
BODY_TYPE"PLUMBING"
HDL_TAP"TRUE";
"B \NAC \NWC"12;
"S \NAC"
BN"1"22;
%"TAP"
"1","(-7875,4950)","2","mstr_standard","I37";
;
CDS_LIB"mstr_standard"
BODY_TYPE"PLUMBING"
HDL_TAP"TRUE";
"B \NAC \NWC"12;
"S \NAC"
BN"0"20;
%"TAP"
"1","(-7875,5050)","2","mstr_standard","I38";
;
CDS_LIB"mstr_standard"
BODY_TYPE"PLUMBING"
HDL_TAP"TRUE";
"B \NAC \NWC"12;
"S \NAC"
BN"2"24;
%"TAP"
"1","(-7875,5100)","2","mstr_standard","I39";
;
CDS_LIB"mstr_standard"
BODY_TYPE"PLUMBING"
HDL_TAP"TRUE";
"B \NAC \NWC"12;
"S \NAC"
BN"3"26;
%"TAP"
"1","(-7875,5150)","2","mstr_standard","I40";
;
CDS_LIB"mstr_standard"
BODY_TYPE"PLUMBING"
HDL_TAP"TRUE";
"B \NAC \NWC"12;
"S \NAC"
BN"4"28;
%"TAP"
"1","(-7875,5250)","2","mstr_standard","I43";
;
CDS_LIB"mstr_standard"
BODY_TYPE"PLUMBING"
HDL_TAP"TRUE";
"B \NAC \NWC"12;
"S \NAC"
BN"6"32;
%"TAP"
"1","(-7875,5200)","2","mstr_standard","I44";
;
CDS_LIB"mstr_standard"
BODY_TYPE"PLUMBING"
HDL_TAP"TRUE";
"B \NAC \NWC"12;
"S \NAC"
BN"5"30;
%"TAP"
"1","(-7875,5350)","2","mstr_standard","I45";
;
CDS_LIB"mstr_standard"
BODY_TYPE"PLUMBING"
HDL_TAP"TRUE";
"B \NAC \NWC"13;
"S \NAC"
BN"0"19;
%"TAP"
"1","(-7875,5400)","2","mstr_standard","I46";
;
CDS_LIB"mstr_standard"
BODY_TYPE"PLUMBING"
HDL_TAP"TRUE";
"B \NAC \NWC"13;
"S \NAC"
BN"1"21;
%"TAP"
"1","(-7875,5450)","2","mstr_standard","I47";
;
CDS_LIB"mstr_standard"
BODY_TYPE"PLUMBING"
HDL_TAP"TRUE";
"B \NAC \NWC"13;
"S \NAC"
BN"2"23;
%"TAP"
"1","(-7875,5500)","2","mstr_standard","I48";
;
CDS_LIB"mstr_standard"
BODY_TYPE"PLUMBING"
HDL_TAP"TRUE";
"B \NAC \NWC"13;
"S \NAC"
BN"3"25;
%"TAP"
"1","(-7875,5550)","2","mstr_standard","I49";
;
CDS_LIB"mstr_standard"
BODY_TYPE"PLUMBING"
HDL_TAP"TRUE";
"B \NAC \NWC"13;
"S \NAC"
BN"4"27;
%"TAP"
"1","(-7875,5600)","2","mstr_standard","I50";
;
CDS_LIB"mstr_standard"
BODY_TYPE"PLUMBING"
HDL_TAP"TRUE";
"B \NAC \NWC"13;
"S \NAC"
BN"5"29;
%"TAP"
"1","(-7875,5650)","2","mstr_standard","I51";
;
CDS_LIB"mstr_standard"
BODY_TYPE"PLUMBING"
HDL_TAP"TRUE";
"B \NAC \NWC"13;
"S \NAC"
BN"6"31;
%"SCONN288_DDR506112002KQ"
"1","(-7025,3900)","0","pure_quanta","I52";
;
LOCATION"J32"
$SEC"1"
CDS_SEC"1"
PART_TYPE"SMLF"
VALUE"SCONN288_DDR506112002KQ"
MATERIAL"IO"
CDS_LMAN_SYM_OUTLINE"-450,1900,450,-1850"
NEEDS_NO_SIZE"TRUE"
CDS_LIB"pure_quanta"
PART_NUMBER"DFHST8FS479";
"PWR_GOOD||FAIL_N"
$PN"147"168;
"DQ31_A"
$PN"194"14;
"CB7_A"
$PN"205"15;
"CB4_A"
$PN"58"16;
"CB1_A"
$PN"53"17;
"CB7_B"
$PN"236"18;
"ALERT_N \B"
$PN"62"160;
"CA0_A"
$PN"66"19;
"CA0_B"
$PN"76"20;
"CA1_A"
$PN"211"21;
"CA1_B"
$PN"221"22;
"CA2_A"
$PN"68"23;
"CA2_B"
$PN"78"24;
"CA3_A"
$PN"213"25;
"CA3_B"
$PN"223"26;
"CA4_A"
$PN"70"27;
"CA4_B"
$PN"80"28;
"CA5_A"
$PN"215"29;
"CA5_B"
$PN"225"30;
"CA6_A"
$PN"72"31;
"CA6_B"
$PN"82"32;
"CB6_A"
$PN"203"33;
"CB5_A"
$PN"60"34;
"CB3_A"
$PN"198"35;
"CB2_A"
$PN"196"36;
"CB0_A"
$PN"51"37;
"CB6_B"
$PN"234"38;
"CB5_B"
$PN"91"39;
"CB4_B"
$PN"89"40;
"CB3_B"
$PN"243"156;
"CB2_B"
$PN"241"157;
"CB1_B"
$PN"98"158;
"CB0_B"
$PN"96"159;
"CK_C \B"
$PN"218"41;
"CK_T"
$PN"217"155;
"CS0_A_N"
$PN"64"42;
"CS0_B_N"
$PN"84"154;
"CS1_A_N"
$PN"209"43;
"CS1_B_N"
$PN"229"44;
"DQ30_A"
$PN"192"45;
"DQ29_A"
$PN"49"46;
"DQ28_A"
$PN"47"47;
"DQ27_A"
$PN"187"48;
"DQ26_A"
$PN"185"49;
"DQ25_A"
$PN"42"50;
"DQ24_A"
$PN"40"51;
"DQ23_A"
$PN"183"52;
"DQ22_A"
$PN"181"53;
"DQ21_A"
$PN"38"54;
"DQ20_A"
$PN"36"55;
"DQ19_A"
$PN"176"56;
"DQ18_A"
$PN"174"57;
"DQ17_A"
$PN"31"58;
"DQ16_A"
$PN"29"59;
"DQ15_A"
$PN"172"60;
"DQ14_A"
$PN"170"61;
"DQ13_A"
$PN"27"62;
"DQ12_A"
$PN"25"63;
"DQ11_A"
$PN"165"64;
"DQ10_A"
$PN"163"65;
"DQ9_A"
$PN"20"151;
"DQ8_A"
$PN"18"66;
"DQ7_A"
$PN"161"67;
"DQ6_A"
$PN"159"68;
"DQ5_A"
$PN"16"69;
"DQ4_A"
$PN"14"70;
"DQ3_A"
$PN"154"71;
"DQ2_A"
$PN"152"72;
"DQ1_A"
$PN"9"73;
"DQ0_A"
$PN"7"74;
"DQ31_B"
$PN"287"75;
"DQ30_B"
$PN"285"76;
"DQ29_B"
$PN"142"77;
"DQ28_B"
$PN"140"78;
"DQ27_B"
$PN"280"79;
"DQ26_B"
$PN"278"80;
"DQ25_B"
$PN"135"81;
"DQ24_B"
$PN"133"82;
"DQ23_B"
$PN"276"83;
"DQ22_B"
$PN"274"84;
"DQ21_B"
$PN"131"85;
"DQ20_B"
$PN"129"86;
"DQ19_B"
$PN"269"87;
"DQ18_B"
$PN"267"88;
"DQ17_B"
$PN"124"89;
"DQ16_B"
$PN"122"90;
"DQ15_B"
$PN"265"91;
"DQ14_B"
$PN"263"92;
"DQ13_B"
$PN"120"152;
"DQ12_B"
$PN"118"93;
"DQ11_B"
$PN"258"94;
"DQ10_B"
$PN"256"95;
"DQ9_B"
$PN"113"96;
"DQ8_B"
$PN"111"97;
"DQ7_B"
$PN"254"98;
"DQ6_B"
$PN"252"99;
"DQ5_B"
$PN"109"100;
"DQ4_B"
$PN"107"101;
"DQ3_B"
$PN"247"102;
"DQ2_B"
$PN"245"103;
"DQ1_B"
$PN"102"104;
"DQ0_B"
$PN"100"105;
"HAS"
$PN"148"162;
"HSCL"
$PN"4"169;
"HSDA"
$PN"5"170;
"LBD||RSP_A_N"
$PN"86"149;
"LBS||RSP_B_N"
$PN"87"106;
"PAR_A"
$PN"74"107;
"PAR_B"
$PN"227"108;
"RESET_N \B"
$PN"207"161;
"RFU6"
$PN"232"0;
"RFU5"
$PN"231"0;
"RFU4"
$PN"220"0;
"RFU3"
$PN"150"0;
"RFU2"
$PN"149"0;
"RFU1"
$PN"144"0;
"RFU0"
$PN"2"0;
"VIN_MGMT"
$PN"3"167;
%"TAP"
"1","(-6175,2550)","0","mstr_standard","I53";
;
CDS_LIB"mstr_standard"
BODY_TYPE"PLUMBING"
HDL_TAP"TRUE";
"B \NAC \NWC"5;
"S \NAC"
BN"2"103;
%"TAP"
"1","(-6175,2600)","0","mstr_standard","I54";
;
CDS_LIB"mstr_standard"
BODY_TYPE"PLUMBING"
HDL_TAP"TRUE";
"B \NAC \NWC"5;
"S \NAC"
BN"3"102;
%"TAP"
"1","(-6175,2450)","0","mstr_standard","I55";
;
CDS_LIB"mstr_standard"
BODY_TYPE"PLUMBING"
HDL_TAP"TRUE";
"B \NAC \NWC"5;
"S \NAC"
BN"0"105;
%"TAP"
"1","(-6175,2500)","0","mstr_standard","I56";
;
CDS_LIB"mstr_standard"
BODY_TYPE"PLUMBING"
HDL_TAP"TRUE";
"B \NAC \NWC"5;
"S \NAC"
BN"1"104;
%"TAP"
"1","(-6175,2650)","0","mstr_standard","I57";
;
CDS_LIB"mstr_standard"
BODY_TYPE"PLUMBING"
HDL_TAP"TRUE";
"B \NAC \NWC"5;
"S \NAC"
BN"4"101;
%"TAP"
"1","(-6175,2700)","0","mstr_standard","I58";
;
CDS_LIB"mstr_standard"
BODY_TYPE"PLUMBING"
HDL_TAP"TRUE";
"B \NAC \NWC"5;
"S \NAC"
BN"5"100;
%"TAP"
"1","(-6175,2750)","0","mstr_standard","I59";
;
CDS_LIB"mstr_standard"
BODY_TYPE"PLUMBING"
HDL_TAP"TRUE";
"B \NAC \NWC"5;
"S \NAC"
BN"6"99;
%"TAP"
"1","(-6175,2800)","0","mstr_standard","I60";
;
CDS_LIB"mstr_standard"
BODY_TYPE"PLUMBING"
HDL_TAP"TRUE";
"B \NAC \NWC"5;
"S \NAC"
BN"7"98;
%"TAP"
"1","(-6175,2850)","0","mstr_standard","I61";
;
CDS_LIB"mstr_standard"
BODY_TYPE"PLUMBING"
HDL_TAP"TRUE";
"B \NAC \NWC"5;
"S \NAC"
BN"8"97;
%"TAP"
"1","(-6175,2900)","0","mstr_standard","I62";
;
CDS_LIB"mstr_standard"
BODY_TYPE"PLUMBING"
HDL_TAP"TRUE";
"B \NAC \NWC"5;
"S \NAC"
BN"9"96;
%"TAP"
"1","(-6175,2950)","0","mstr_standard","I63";
;
CDS_LIB"mstr_standard"
BODY_TYPE"PLUMBING"
HDL_TAP"TRUE";
"B \NAC \NWC"5;
"S \NAC"
BN"10"95;
%"TAP"
"1","(-6175,3000)","0","mstr_standard","I64";
;
CDS_LIB"mstr_standard"
BODY_TYPE"PLUMBING"
HDL_TAP"TRUE";
"B \NAC \NWC"5;
"S \NAC"
BN"11"94;
%"TAP"
"1","(-6175,3100)","0","mstr_standard","I65";
;
CDS_LIB"mstr_standard"
BODY_TYPE"PLUMBING"
HDL_TAP"TRUE";
"B \NAC \NWC"5;
"S \NAC"
BN"13"152;
%"TAP"
"1","(-6175,3050)","0","mstr_standard","I66";
;
CDS_LIB"mstr_standard"
BODY_TYPE"PLUMBING"
HDL_TAP"TRUE";
"B \NAC \NWC"5;
"S \NAC"
BN"12"93;
%"TAP"
"1","(-6175,3200)","0","mstr_standard","I67";
;
CDS_LIB"mstr_standard"
BODY_TYPE"PLUMBING"
HDL_TAP"TRUE";
"B \NAC \NWC"5;
"S \NAC"
BN"15"91;
%"TAP"
"1","(-6175,3150)","0","mstr_standard","I68";
;
CDS_LIB"mstr_standard"
BODY_TYPE"PLUMBING"
HDL_TAP"TRUE";
"B \NAC \NWC"5;
"S \NAC"
BN"14"92;
%"TAP"
"1","(-6175,3250)","0","mstr_standard","I69";
;
CDS_LIB"mstr_standard"
BODY_TYPE"PLUMBING"
HDL_TAP"TRUE";
"B \NAC \NWC"5;
"S \NAC"
BN"16"90;
%"TAP"
"1","(-6175,3350)","0","mstr_standard","I70";
;
CDS_LIB"mstr_standard"
BODY_TYPE"PLUMBING"
HDL_TAP"TRUE";
"B \NAC \NWC"5;
"S \NAC"
BN"18"88;
%"TAP"
"1","(-6175,3400)","0","mstr_standard","I71";
;
CDS_LIB"mstr_standard"
BODY_TYPE"PLUMBING"
HDL_TAP"TRUE";
"B \NAC \NWC"5;
"S \NAC"
BN"19"87;
%"TAP"
"1","(-6175,3300)","0","mstr_standard","I72";
;
CDS_LIB"mstr_standard"
BODY_TYPE"PLUMBING"
HDL_TAP"TRUE";
"B \NAC \NWC"5;
"S \NAC"
BN"17"89;
%"TAP"
"1","(-6175,3500)","0","mstr_standard","I73";
;
CDS_LIB"mstr_standard"
BODY_TYPE"PLUMBING"
HDL_TAP"TRUE";
"B \NAC \NWC"5;
"S \NAC"
BN"21"85;
%"TAP"
"1","(-6175,3450)","0","mstr_standard","I74";
;
CDS_LIB"mstr_standard"
BODY_TYPE"PLUMBING"
HDL_TAP"TRUE";
"B \NAC \NWC"5;
"S \NAC"
BN"20"86;
%"TAP"
"1","(-6175,3550)","0","mstr_standard","I75";
;
CDS_LIB"mstr_standard"
BODY_TYPE"PLUMBING"
HDL_TAP"TRUE";
"B \NAC \NWC"5;
"S \NAC"
BN"22"84;
%"TAP"
"1","(-6175,3650)","0","mstr_standard","I76";
;
CDS_LIB"mstr_standard"
BODY_TYPE"PLUMBING"
HDL_TAP"TRUE";
"B \NAC \NWC"5;
"S \NAC"
BN"24"82;
%"TAP"
"1","(-6175,3600)","0","mstr_standard","I77";
;
CDS_LIB"mstr_standard"
BODY_TYPE"PLUMBING"
HDL_TAP"TRUE";
"B \NAC \NWC"5;
"S \NAC"
BN"23"83;
%"TAP"
"1","(-6175,3750)","0","mstr_standard","I78";
;
CDS_LIB"mstr_standard"
BODY_TYPE"PLUMBING"
HDL_TAP"TRUE";
"B \NAC \NWC"5;
"S \NAC"
BN"26"80;
%"TAP"
"1","(-6175,3700)","0","mstr_standard","I79";
;
CDS_LIB"mstr_standard"
BODY_TYPE"PLUMBING"
HDL_TAP"TRUE";
"B \NAC \NWC"5;
"S \NAC"
BN"25"81;
%"TAP"
"1","(-6175,3800)","0","mstr_standard","I80";
;
CDS_LIB"mstr_standard"
BODY_TYPE"PLUMBING"
HDL_TAP"TRUE";
"B \NAC \NWC"5;
"S \NAC"
BN"27"79;
%"TAP"
"1","(-6175,3900)","0","mstr_standard","I81";
;
CDS_LIB"mstr_standard"
BODY_TYPE"PLUMBING"
HDL_TAP"TRUE";
"B \NAC \NWC"5;
"S \NAC"
BN"29"77;
%"TAP"
"1","(-6175,3850)","0","mstr_standard","I82";
;
CDS_LIB"mstr_standard"
BODY_TYPE"PLUMBING"
HDL_TAP"TRUE";
"B \NAC \NWC"5;
"S \NAC"
BN"28"78;
%"TAP"
"1","(-6175,3950)","0","mstr_standard","I83";
;
CDS_LIB"mstr_standard"
BODY_TYPE"PLUMBING"
HDL_TAP"TRUE";
"B \NAC \NWC"5;
"S \NAC"
BN"30"76;
%"TAP"
"1","(-6175,4000)","0","mstr_standard","I84";
;
CDS_LIB"mstr_standard"
BODY_TYPE"PLUMBING"
HDL_TAP"TRUE";
"B \NAC \NWC"5;
"S \NAC"
BN"31"75;
%"TAP"
"1","(-6175,4150)","0","mstr_standard","I85";
;
CDS_LIB"mstr_standard"
BODY_TYPE"PLUMBING"
HDL_TAP"TRUE";
"B \NAC \NWC"6;
"S \NAC"
BN"1"73;
%"TAP"
"1","(-6175,4100)","0","mstr_standard","I86";
;
CDS_LIB"mstr_standard"
BODY_TYPE"PLUMBING"
HDL_TAP"TRUE";
"B \NAC \NWC"6;
"S \NAC"
BN"0"74;
%"TAP"
"1","(-6175,4200)","0","mstr_standard","I95";
;
CDS_LIB"mstr_standard"
BODY_TYPE"PLUMBING"
HDL_TAP"TRUE";
"B \NAC \NWC"6;
"S \NAC"
BN"2"72;
%"TAP"
"1","(-6175,4250)","0","mstr_standard","I96";
;
CDS_LIB"mstr_standard"
BODY_TYPE"PLUMBING"
HDL_TAP"TRUE";
"B \NAC \NWC"6;
"S \NAC"
BN"3"71;
%"TAP"
"1","(-6175,4300)","0","mstr_standard","I97";
;
CDS_LIB"mstr_standard"
BODY_TYPE"PLUMBING"
HDL_TAP"TRUE";
"B \NAC \NWC"6;
"S \NAC"
BN"4"70;
%"TAP"
"1","(-6175,4400)","0","mstr_standard","I98";
;
CDS_LIB"mstr_standard"
BODY_TYPE"PLUMBING"
HDL_TAP"TRUE";
"B \NAC \NWC"6;
"S \NAC"
BN"6"68;
%"TAP"
"1","(-6175,4350)","0","mstr_standard","I99";
;
CDS_LIB"mstr_standard"
BODY_TYPE"PLUMBING"
HDL_TAP"TRUE";
"B \NAC \NWC"6;
"S \NAC"
BN"5"69;
END.
